(kicad_pcb
	(version 20260206)
	(generator "pcbnew")
	(generator_version "10.0")
	(general
		(thickness 1.6)
		(legacy_teardrops no)
	)
	(paper "A4")
	(title_block
		(title "Bryce Canyon_SCC_16316-1_OCP.brd")
		(comment 1 "Bryce Canyon / footprints 711-719 of 1561")
	)
	(layers
		(0 "F.Cu" signal "TOP")
		(4 "In1.Cu" signal "L2GND")
		(6 "In2.Cu" signal "L3")
		(8 "In3.Cu" signal "L4VCC")
		(10 "In4.Cu" signal "L5VCC")
		(12 "In5.Cu" signal "L6")
		(14 "In6.Cu" signal "L7GND")
		(2 "B.Cu" signal "BOTTOM")
		(9 "F.Adhes" user "F.Adhesive")
		(11 "B.Adhes" user "B.Adhesive")
		(13 "F.Paste" user "Package Geometry/Pastemask Top")
		(15 "B.Paste" user "Package Geometry/Pastemask Bottom")
		(5 "F.SilkS" user "Ref Des/Silkscreen Top")
		(7 "B.SilkS" user "Ref Des/Silkscreen Bottom")
		(1 "F.Mask" user "Board Geometry/Soldermask Top")
		(3 "B.Mask" user "Board Geometry/Soldermask Bottom")
		(17 "Dwgs.User" user "User.Drawings")
		(19 "Cmts.User" user "User.Comments")
		(21 "Eco1.User" user "User.Eco1")
		(23 "Eco2.User" user "User.Eco2")
		(25 "Edge.Cuts" user "Board Geometry/Outline")
		(27 "Margin" user)
		(31 "F.CrtYd" user "Package Geometry/Place Bound Top")
		(29 "B.CrtYd" user "Package Geometry/Place Bound Bottom")
		(35 "F.Fab" user "Ref Des/Assembly Top")
		(33 "B.Fab" user "Ref Des/Assembly Bottom")
	)
	(footprint ""
		(layer "F.Cu")
		(at 194.2846 -33.2232 -90)
		(property "Reference" "TP87"
			(at 0 0 270)
			(layer "F.SilkS")
			(hide yes)
			(effects
				(font
					(size 1.27 1.27)
				)
			)
		)
		(property "Value" "TPAD28-2-GP"
			(at -0.0127 -1.6637 270)
			(unlocked yes)
			(layer "F.Fab")
			(hide yes)
			(effects
				(font
					(size 1.016 1.016)
					(thickness 0.1524)
				)
			)
		)
		(property "Device Type" "TPAD28"
			(at -0.0127 -3.1877 270)
			(unlocked yes)
			(layer "F.Fab")
			(hide yes)
			(effects
				(font
					(size 1.016 1.016)
					(thickness 0.1524)
				)
			)
		)
		(duplicate_pad_numbers_are_jumpers no)
		(fp_poly
			(pts
				(arc
					(start 0 -0.3556)
					(mid 0 0.3556)
					(end 0 -0.3556)
				)
			)
			(stroke
				(width 0)
				(type default)
			)
			(fill no)
			(layer "F.CrtYd")
		)
		(fp_poly
			(pts
				(arc
					(start 0 -0.6096)
					(mid 0 0.6096)
					(end 0 -0.6096)
				)
			)
			(stroke
				(width 0)
				(type default)
			)
			(fill no)
			(layer "F.Fab")
		)
		(pad "1" smd circle
			(at 0 0 270)
			(size 0.7112 0.7112)
			(layers "F.Cu" "F.Mask" "F.Paste")
			(net "IOC_GPIO_30")
		)
	)
	(footprint ""
		(layer "F.Cu")
		(at 118.1862 -89.276174)
		(property "Reference" "TP50"
			(at 0 0 0)
			(layer "F.SilkS")
			(hide yes)
			(effects
				(font
					(size 1.27 1.27)
				)
			)
		)
		(property "Value" "TPAD28-2-GP"
			(at -0.0127 -1.6637 0)
			(unlocked yes)
			(layer "F.Fab")
			(hide yes)
			(effects
				(font
					(size 1.016 1.016)
					(thickness 0.1524)
				)
			)
		)
		(property "Device Type" "TPAD28"
			(at -0.0127 -3.1877 0)
			(unlocked yes)
			(layer "F.Fab")
			(hide yes)
			(effects
				(font
					(size 1.016 1.016)
					(thickness 0.1524)
				)
			)
		)
		(duplicate_pad_numbers_are_jumpers no)
		(fp_poly
			(pts
				(arc
					(start 0.3556 0)
					(mid -0.3556 0)
					(end 0.3556 0)
				)
			)
			(stroke
				(width 0)
				(type default)
			)
			(fill no)
			(layer "F.CrtYd")
		)
		(fp_poly
			(pts
				(arc
					(start 0.6096 0)
					(mid -0.6096 0)
					(end 0.6096 0)
				)
			)
			(stroke
				(width 0)
				(type default)
			)
			(fill no)
			(layer "F.Fab")
		)
		(pad "1" smd circle
			(at 0 0)
			(size 0.7112 0.7112)
			(layers "F.Cu" "F.Mask" "F.Paste")
			(net "EXP_XM_ADDR_0")
		)
	)
	(footprint ""
		(layer "F.Cu")
		(at 94.1832 -73.152 90)
		(property "Reference" "R34"
			(at 0 0 90)
			(layer "F.SilkS")
			(hide yes)
			(effects
				(font
					(size 1.27 1.27)
				)
			)
		)
		(property "Value" "4K75R2F-1-GP"
			(at 0.064008 -3.993896 90)
			(unlocked yes)
			(layer "F.Fab")
			(hide yes)
			(effects
				(font
					(size 1.016 1.016)
					(thickness 0.1524)
				)
			)
		)
		(property "Device Type" "R402H16"
			(at 0.064008 -5.517896 90)
			(unlocked yes)
			(layer "F.Fab")
			(hide yes)
			(effects
				(font
					(size 1.016 1.016)
					(thickness 0.1524)
				)
			)
		)
		(duplicate_pad_numbers_are_jumpers no)
		(fp_line
			(start 0.508 -0.9398)
			(end -0.508 -0.9398)
			(stroke
				(width 0.1524)
				(type default)
			)
			(layer "F.SilkS")
		)
		(fp_line
			(start -0.508 -0.9398)
			(end -0.508 0.9398)
			(stroke
				(width 0.1524)
				(type default)
			)
			(layer "F.SilkS")
		)
		(fp_rect
			(start -0.508 0.9398)
			(end 0.508 -0.9398)
			(stroke
				(width 0)
				(type default)
			)
			(fill no)
			(layer "F.CrtYd")
		)
		(fp_rect
			(start -0.508 0.9398)
			(end 0.508 -0.9398)
			(stroke
				(width 0)
				(type default)
			)
			(fill no)
			(layer "F.Fab")
		)
		(pad "1" smd custom
			(at 0 -0.4445 90)
			(size 0.1397 0.1397)
			(layers "F.Cu" "F.Mask" "F.Paste")
			(net "GND")
			(options
				(clearance outline)
				(anchor circle)
			)
			(primitives
				(gr_poly
					(pts
						(arc
							(start -0.1778 -0.2794)
							(mid -0.249642 -0.249642)
							(end -0.2794 -0.1778)
						)
						(arc
							(start -0.2794 0.1778)
							(mid -0.249642 0.249642)
							(end -0.1778 0.2794)
						)
						(arc
							(start 0.1778 0.2794)
							(mid 0.249642 0.249642)
							(end 0.2794 0.1778)
						)
						(arc
							(start 0.2794 -0.1778)
							(mid 0.249642 -0.249642)
							(end 0.1778 -0.2794)
						)
					)
					(width 0)
					(fill yes)
				)
			)
		)
		(pad "2" smd custom
			(at 0 0.4445 90)
			(size 0.1397 0.1397)
			(layers "F.Cu" "F.Mask" "F.Paste")
			(net "EXP_ADC_IN1")
			(options
				(clearance outline)
				(anchor circle)
			)
			(primitives
				(gr_poly
					(pts
						(arc
							(start -0.1778 -0.2794)
							(mid -0.249642 -0.249642)
							(end -0.2794 -0.1778)
						)
						(arc
							(start -0.2794 0.1778)
							(mid -0.249642 0.249642)
							(end -0.1778 0.2794)
						)
						(arc
							(start 0.1778 0.2794)
							(mid 0.249642 0.249642)
							(end 0.2794 0.1778)
						)
						(arc
							(start 0.2794 -0.1778)
							(mid 0.249642 -0.249642)
							(end 0.1778 -0.2794)
						)
					)
					(width 0)
					(fill yes)
				)
			)
		)
	)
	(footprint ""
		(layer "F.Cu")
		(at 19.5072 -46.9646)
		(property "Reference" "R16"
			(at 0 0 0)
			(layer "F.SilkS")
			(hide yes)
			(effects
				(font
					(size 1.27 1.27)
				)
			)
		)
		(property "Value" "5K1R2F-3-GP"
			(at 0.064008 -3.993896 0)
			(unlocked yes)
			(layer "F.Fab")
			(hide yes)
			(effects
				(font
					(size 1.016 1.016)
					(thickness 0.1524)
				)
			)
		)
		(property "Device Type" "R402H16"
			(at 0.064008 -5.517896 0)
			(unlocked yes)
			(layer "F.Fab")
			(hide yes)
			(effects
				(font
					(size 1.016 1.016)
					(thickness 0.1524)
				)
			)
		)
		(duplicate_pad_numbers_are_jumpers no)
		(fp_line
			(start -0.508 -0.9398)
			(end -0.508 0.9398)
			(stroke
				(width 0.1524)
				(type default)
			)
			(layer "F.SilkS")
		)
		(fp_line
			(start 0.508 -0.9398)
			(end -0.508 -0.9398)
			(stroke
				(width 0.1524)
				(type default)
			)
			(layer "F.SilkS")
		)
		(fp_rect
			(start -0.508 0.9398)
			(end 0.508 -0.9398)
			(stroke
				(width 0)
				(type default)
			)
			(fill no)
			(layer "F.CrtYd")
		)
		(fp_rect
			(start -0.508 0.9398)
			(end 0.508 -0.9398)
			(stroke
				(width 0)
				(type default)
			)
			(fill no)
			(layer "F.Fab")
		)
		(pad "1" smd custom
			(at 0 -0.4445)
			(size 0.1397 0.1397)
			(layers "F.Cu" "F.Mask" "F.Paste")
			(net "MB0_CM_UV_R")
			(options
				(clearance outline)
				(anchor circle)
			)
			(primitives
				(gr_poly
					(pts
						(arc
							(start -0.1778 -0.2794)
							(mid -0.249642 -0.249642)
							(end -0.2794 -0.1778)
						)
						(arc
							(start -0.2794 0.1778)
							(mid -0.249642 0.249642)
							(end -0.1778 0.2794)
						)
						(arc
							(start 0.1778 0.2794)
							(mid 0.249642 0.249642)
							(end 0.2794 0.1778)
						)
						(arc
							(start 0.2794 -0.1778)
							(mid 0.249642 -0.249642)
							(end 0.1778 -0.2794)
						)
					)
					(width 0)
					(fill yes)
				)
			)
		)
		(pad "2" smd custom
			(at 0 0.4445)
			(size 0.1397 0.1397)
			(layers "F.Cu" "F.Mask" "F.Paste")
			(net "AGND_CURRENT_MON")
			(options
				(clearance outline)
				(anchor circle)
			)
			(primitives
				(gr_poly
					(pts
						(arc
							(start -0.1778 -0.2794)
							(mid -0.249642 -0.249642)
							(end -0.2794 -0.1778)
						)
						(arc
							(start -0.2794 0.1778)
							(mid -0.249642 0.249642)
							(end -0.1778 0.2794)
						)
						(arc
							(start 0.1778 0.2794)
							(mid 0.249642 0.249642)
							(end 0.2794 0.1778)
						)
						(arc
							(start 0.2794 -0.1778)
							(mid 0.249642 -0.249642)
							(end 0.1778 -0.2794)
						)
					)
					(width 0)
					(fill yes)
				)
			)
		)
	)
	(footprint ""
		(layer "F.Cu")
		(at 170.33494 -105.95102 180)
		(property "Reference" "R376"
			(at 0 0 180)
			(layer "F.SilkS")
			(hide yes)
			(effects
				(font
					(size 1.27 1.27)
				)
			)
		)
		(property "Value" "4K7R2F-GP"
			(at 0.064008 -3.993896 180)
			(unlocked yes)
			(layer "F.Fab")
			(hide yes)
			(effects
				(font
					(size 1.016 1.016)
					(thickness 0.1524)
				)
			)
		)
		(property "Device Type" "R402H16"
			(at 0.064008 -5.517896 180)
			(unlocked yes)
			(layer "F.Fab")
			(hide yes)
			(effects
				(font
					(size 1.016 1.016)
					(thickness 0.1524)
				)
			)
		)
		(duplicate_pad_numbers_are_jumpers no)
		(fp_line
			(start 0.508 -0.9398)
			(end -0.508 -0.9398)
			(stroke
				(width 0.1524)
				(type default)
			)
			(layer "F.SilkS")
		)
		(fp_line
			(start -0.508 -0.9398)
			(end -0.508 0.9398)
			(stroke
				(width 0.1524)
				(type default)
			)
			(layer "F.SilkS")
		)
		(fp_rect
			(start -0.508 0.9398)
			(end 0.508 -0.9398)
			(stroke
				(width 0)
				(type default)
			)
			(fill no)
			(layer "F.CrtYd")
		)
		(fp_rect
			(start -0.508 0.9398)
			(end 0.508 -0.9398)
			(stroke
				(width 0)
				(type default)
			)
			(fill no)
			(layer "F.Fab")
		)
		(pad "1" smd custom
			(at 0 -0.4445 180)
			(size 0.1397 0.1397)
			(layers "F.Cu" "F.Mask" "F.Paste")
			(net "P1V8_C")
			(options
				(clearance outline)
				(anchor circle)
			)
			(primitives
				(gr_poly
					(pts
						(arc
							(start -0.1778 -0.2794)
							(mid -0.249642 -0.249642)
							(end -0.2794 -0.1778)
						)
						(arc
							(start -0.2794 0.1778)
							(mid -0.249642 0.249642)
							(end -0.1778 0.2794)
						)
						(arc
							(start 0.1778 0.2794)
							(mid 0.249642 0.249642)
							(end 0.2794 0.1778)
						)
						(arc
							(start 0.2794 -0.1778)
							(mid 0.249642 -0.249642)
							(end 0.1778 -0.2794)
						)
					)
					(width 0)
					(fill yes)
				)
			)
		)
		(pad "2" smd custom
			(at 0 0.4445 180)
			(size 0.1397 0.1397)
			(layers "F.Cu" "F.Mask" "F.Paste")
			(net "SCC_FULL_PGOOD_LS")
			(options
				(clearance outline)
				(anchor circle)
			)
			(primitives
				(gr_poly
					(pts
						(arc
							(start -0.1778 -0.2794)
							(mid -0.249642 -0.249642)
							(end -0.2794 -0.1778)
						)
						(arc
							(start -0.2794 0.1778)
							(mid -0.249642 0.249642)
							(end -0.1778 0.2794)
						)
						(arc
							(start 0.1778 0.2794)
							(mid 0.249642 0.249642)
							(end 0.2794 0.1778)
						)
						(arc
							(start 0.2794 -0.1778)
							(mid 0.249642 -0.249642)
							(end 0.1778 -0.2794)
						)
					)
					(width 0)
					(fill yes)
				)
			)
		)
	)
	(footprint ""
		(layer "F.Cu")
		(at 193.1543 -30.3657 -90)
		(property "Reference" "TP53"
			(at 0 0 270)
			(layer "F.SilkS")
			(hide yes)
			(effects
				(font
					(size 1.27 1.27)
				)
			)
		)
		(property "Value" "TPAD28-2-GP"
			(at -0.0127 -1.6637 270)
			(unlocked yes)
			(layer "F.Fab")
			(hide yes)
			(effects
				(font
					(size 1.016 1.016)
					(thickness 0.1524)
				)
			)
		)
		(property "Device Type" "TPAD28"
			(at -0.0127 -3.1877 270)
			(unlocked yes)
			(layer "F.Fab")
			(hide yes)
			(effects
				(font
					(size 1.016 1.016)
					(thickness 0.1524)
				)
			)
		)
		(duplicate_pad_numbers_are_jumpers no)
		(fp_poly
			(pts
				(arc
					(start 0 -0.3556)
					(mid 0 0.3556)
					(end 0 -0.3556)
				)
			)
			(stroke
				(width 0)
				(type default)
			)
			(fill no)
			(layer "F.CrtYd")
		)
		(fp_poly
			(pts
				(arc
					(start 0 -0.6096)
					(mid 0 0.6096)
					(end 0 -0.6096)
				)
			)
			(stroke
				(width 0)
				(type default)
			)
			(fill no)
			(layer "F.Fab")
		)
		(pad "1" smd circle
			(at 0 0 270)
			(size 0.7112 0.7112)
			(layers "F.Cu" "F.Mask" "F.Paste")
			(net "IOC_GPIO_0")
		)
	)
	(footprint ""
		(layer "F.Cu")
		(at 136.227312 -79.171292 90)
		(property "Reference" "C678"
			(at 0 0 90)
			(layer "F.SilkS")
			(hide yes)
			(effects
				(font
					(size 1.27 1.27)
				)
			)
		)
		(property "Value" "SCD01U16V1KX-GP"
			(at -2.8321 -1.7399 90)
			(unlocked yes)
			(layer "F.Fab")
			(hide yes)
			(effects
				(font
					(size 1.016 1.016)
					(thickness 0.1524)
				)
			)
		)
		(property "Device Type" "C0201H13"
			(at -2.8321 -3.2639 90)
			(unlocked yes)
			(layer "F.Fab")
			(hide yes)
			(effects
				(font
					(size 1.016 1.016)
					(thickness 0.1524)
				)
			)
		)
		(duplicate_pad_numbers_are_jumpers no)
		(fp_rect
			(start -0.2794 0.6477)
			(end 0.2794 -0.6477)
			(stroke
				(width 0)
				(type default)
			)
			(fill no)
			(layer "F.CrtYd")
		)
		(fp_rect
			(start -0.2794 0.6477)
			(end 0.2794 -0.6477)
			(stroke
				(width 0)
				(type default)
			)
			(fill no)
			(layer "F.Fab")
		)
		(pad "1" smd custom
			(at 0 -0.2794 90)
			(size 0.0762 0.0762)
			(layers "F.Cu" "F.Mask" "F.Paste")
			(net "PHY_EXP_TO_CONN_C_10_DP")
			(options
				(clearance outline)
				(anchor circle)
			)
			(primitives
				(gr_poly
					(pts
						(arc
							(start 0.1524 -0.127)
							(mid 0.137521 -0.162921)
							(end 0.1016 -0.1778)
						)
						(arc
							(start -0.1016 -0.1778)
							(mid -0.137521 -0.162921)
							(end -0.1524 -0.127)
						)
						(arc
							(start -0.1524 0.127)
							(mid -0.137521 0.162921)
							(end -0.1016 0.1778)
						)
						(arc
							(start 0.1016 0.1778)
							(mid 0.137521 0.162921)
							(end 0.1524 0.127)
						)
					)
					(width 0)
					(fill yes)
				)
			)
		)
		(pad "2" smd custom
			(at 0 0.2794 90)
			(size 0.0762 0.0762)
			(layers "F.Cu" "F.Mask" "F.Paste")
			(net "PHY_EXP_TO_CONN_10_DP")
			(options
				(clearance outline)
				(anchor circle)
			)
			(primitives
				(gr_poly
					(pts
						(arc
							(start 0.1524 -0.127)
							(mid 0.137521 -0.162921)
							(end 0.1016 -0.1778)
						)
						(arc
							(start -0.1016 -0.1778)
							(mid -0.137521 -0.162921)
							(end -0.1524 -0.127)
						)
						(arc
							(start -0.1524 0.127)
							(mid -0.137521 0.162921)
							(end -0.1016 0.1778)
						)
						(arc
							(start 0.1016 0.1778)
							(mid 0.137521 0.162921)
							(end 0.1524 0.127)
						)
					)
					(width 0)
					(fill yes)
				)
			)
		)
	)
	(footprint ""
		(layer "F.Cu")
		(at 134.341108 -86.79815)
		(property "Reference" "TP17"
			(at 0 0 0)
			(layer "F.SilkS")
			(hide yes)
			(effects
				(font
					(size 1.27 1.27)
				)
			)
		)
		(property "Value" "TPAD28-2-GP"
			(at -0.0127 -1.6637 0)
			(unlocked yes)
			(layer "F.Fab")
			(hide yes)
			(effects
				(font
					(size 1.016 1.016)
					(thickness 0.1524)
				)
			)
		)
		(property "Device Type" "TPAD28"
			(at -0.0127 -3.1877 0)
			(unlocked yes)
			(layer "F.Fab")
			(hide yes)
			(effects
				(font
					(size 1.016 1.016)
					(thickness 0.1524)
				)
			)
		)
		(duplicate_pad_numbers_are_jumpers no)
		(fp_poly
			(pts
				(arc
					(start 0.3556 0)
					(mid -0.3556 0)
					(end 0.3556 0)
				)
			)
			(stroke
				(width 0)
				(type default)
			)
			(fill no)
			(layer "F.CrtYd")
		)
		(fp_poly
			(pts
				(arc
					(start 0.6096 0)
					(mid -0.6096 0)
					(end 0.6096 0)
				)
			)
			(stroke
				(width 0)
				(type default)
			)
			(fill no)
			(layer "F.Fab")
		)
		(pad "1" smd circle
			(at 0 0)
			(size 0.7112 0.7112)
			(layers "F.Cu" "F.Mask" "F.Paste")
			(net "EXP_I2C_SDA10")
		)
	)
	(footprint ""
		(layer "F.Cu")
		(at 19.252184 -70.28053 90)
		(property "Reference" "R355"
			(at 0 0 90)
			(layer "F.SilkS")
			(hide yes)
			(effects
				(font
					(size 1.27 1.27)
				)
			)
		)
		(property "Value" "0R2J-2-GP"
			(at 0.064008 -3.993896 90)
			(unlocked yes)
			(layer "F.Fab")
			(hide yes)
			(effects
				(font
					(size 1.016 1.016)
					(thickness 0.1524)
				)
			)
		)
		(property "Device Type" "R402H16"
			(at 0.064008 -5.517896 90)
			(unlocked yes)
			(layer "F.Fab")
			(hide yes)
			(effects
				(font
					(size 1.016 1.016)
					(thickness 0.1524)
				)
			)
		)
		(duplicate_pad_numbers_are_jumpers no)
		(fp_line
			(start 0.508 -0.9398)
			(end -0.508 -0.9398)
			(stroke
				(width 0.1524)
				(type default)
			)
			(layer "F.SilkS")
		)
		(fp_line
			(start -0.508 -0.9398)
			(end -0.508 0.9398)
			(stroke
				(width 0.1524)
				(type default)
			)
			(layer "F.SilkS")
		)
		(fp_rect
			(start -0.508 0.9398)
			(end 0.508 -0.9398)
			(stroke
				(width 0)
				(type default)
			)
			(fill no)
			(layer "F.CrtYd")
		)
		(fp_rect
			(start -0.508 0.9398)
			(end 0.508 -0.9398)
			(stroke
				(width 0)
				(type default)
			)
			(fill no)
			(layer "F.Fab")
		)
		(pad "1" smd custom
			(at 0 -0.4445 90)
			(size 0.1397 0.1397)
			(layers "F.Cu" "F.Mask" "F.Paste")
			(net "EEPROM_SDA")
			(options
				(clearance outline)
				(anchor circle)
			)
			(primitives
				(gr_poly
					(pts
						(arc
							(start -0.1778 -0.2794)
							(mid -0.249642 -0.249642)
							(end -0.2794 -0.1778)
						)
						(arc
							(start -0.2794 0.1778)
							(mid -0.249642 0.249642)
							(end -0.1778 0.2794)
						)
						(arc
							(start 0.1778 0.2794)
							(mid 0.249642 0.249642)
							(end 0.2794 0.1778)
						)
						(arc
							(start 0.2794 -0.1778)
							(mid 0.249642 -0.249642)
							(end 0.1778 -0.2794)
						)
					)
					(width 0)
					(fill yes)
				)
			)
		)
		(pad "2" smd custom
			(at 0 0.4445 90)
			(size 0.1397 0.1397)
			(layers "F.Cu" "F.Mask" "F.Paste")
			(net "I2C_SCC_SDA2")
			(options
				(clearance outline)
				(anchor circle)
			)
			(primitives
				(gr_poly
					(pts
						(arc
							(start -0.1778 -0.2794)
							(mid -0.249642 -0.249642)
							(end -0.2794 -0.1778)
						)
						(arc
							(start -0.2794 0.1778)
							(mid -0.249642 0.249642)
							(end -0.1778 0.2794)
						)
						(arc
							(start 0.1778 0.2794)
							(mid 0.249642 0.249642)
							(end 0.2794 0.1778)
						)
						(arc
							(start 0.2794 -0.1778)
							(mid 0.249642 -0.249642)
							(end 0.1778 -0.2794)
						)
					)
					(width 0)
					(fill yes)
				)
			)
		)
	)
)
